# S9S_MB_2U (Grand Teton) — schematic netlist excerpt (pin names and nets, part order shuffled) for the footprints in the layout excerpt that follows; sources: Cadence DE-HDL packaged netlist, KiCad conversion of 03242023_DA0F0TMBIJ0_F0T_Motherboard_J_brd_V01_OCP.brd

PR4541  Q_RES  20K 1% CHIP  pkg 0402LF  page 193 : A = P12V_E1S_ISET_0 ; B = P12V_E1S_ISET_0_R
PC2186  Q_CAP  1UF 25V 10% X6S  pkg C0402  page 301 : A = HSC_VDD_R ; B = AGND_HSC

(kicad_pcb
	(version 20260206)
	(generator "pcbnew")
	(generator_version "10.0")
	(general
		(thickness 1.6)
		(legacy_teardrops no)
	)
	(paper "A4")
	(title_block
		(title "03242023_DA0F0TMBIJ0_F0T_Motherboard_J_brd_V01_OCP.brd")
		(comment 1 "Grand Teton / footprints 5048-5049 of 6105")
	)
	(layers
		(0 "F.Cu" signal "TOP")
		(4 "In1.Cu" signal "GND")
		(6 "In2.Cu" signal "IN1")
		(8 "In3.Cu" signal "GND1")
		(10 "In4.Cu" signal "IN2")
		(12 "In5.Cu" signal "GND2")
		(14 "In6.Cu" signal "IN3")
		(16 "In7.Cu" signal "GND3")
		(18 "In8.Cu" signal "VCC")
		(20 "In9.Cu" signal "VCC1")
		(22 "In10.Cu" signal "GND4")
		(24 "In11.Cu" signal "IN4")
		(26 "In12.Cu" signal "GND5")
		(28 "In13.Cu" signal "IN5")
		(30 "In14.Cu" signal "GND6")
		(32 "In15.Cu" signal "IN6")
		(34 "In16.Cu" signal "GND7")
		(2 "B.Cu" signal "BOTTOM")
		(9 "F.Adhes" user "F.Adhesive")
		(11 "B.Adhes" user "B.Adhesive")
		(13 "F.Paste" user "Package Geometry/Pastemask Top")
		(15 "B.Paste" user "Package Geometry/Pastemask Bottom")
		(5 "F.SilkS" user "Ref Des/Silkscreen Top")
		(7 "B.SilkS" user "Ref Des/Silkscreen Bottom")
		(1 "F.Mask" user "Board Geometry/Soldermask Top")
		(3 "B.Mask" user "Board Geometry/Soldermask Bottom")
		(17 "Dwgs.User" user "User.Drawings")
		(19 "Cmts.User" user "User.Comments")
		(21 "Eco1.User" user "User.Eco1")
		(23 "Eco2.User" user "User.Eco2")
		(25 "Edge.Cuts" user "Board Geometry/Outline")
		(27 "Margin" user)
		(31 "F.CrtYd" user "Package Geometry/Place Bound Top")
		(29 "B.CrtYd" user "Package Geometry/Place Bound Bottom")
		(35 "F.Fab" user "Ref Des/Assembly Top")
		(33 "B.Fab" user "Ref Des/Assembly Bottom")
	)
	(footprint ""
		(layer "B.Cu")
		(at 184.010808 -402.721572 -90)
		(property "Reference" "PC2186"
			(at 0 0 90)
			(layer "B.SilkS")
			(hide yes)
			(effects
				(font
					(size 1.27 1.27)
				)
				(justify mirror)
			)
		)
		(property "Value" ""
			(at 0 0 90)
			(layer "B.Fab")
			(effects
				(font
					(size 1.27 1.27)
				)
				(justify mirror)
			)
		)
		(duplicate_pad_numbers_are_jumpers no)
		(fp_line
			(start -0.7874 0.4064)
			(end 0.7874 0.4064)
			(stroke
				(width 0.1524)
				(type default)
			)
			(layer "B.SilkS")
		)
		(fp_line
			(start 0.7874 0.4064)
			(end 0.7874 -0.4064)
			(stroke
				(width 0.1524)
				(type default)
			)
			(layer "B.SilkS")
		)
		(fp_line
			(start -0.7874 -0.4064)
			(end -0.7874 0.4064)
			(stroke
				(width 0.1524)
				(type default)
			)
			(layer "B.SilkS")
		)
		(fp_line
			(start 0.7874 -0.4064)
			(end -0.7874 -0.4064)
			(stroke
				(width 0.1524)
				(type default)
			)
			(layer "B.SilkS")
		)
		(fp_line
			(start -0.67945 0.3048)
			(end -0.120396 0.3048)
			(stroke
				(width 0.1)
				(type default)
			)
			(layer "B.Fab")
		)
		(fp_line
			(start -0.120396 0.3048)
			(end -0.120396 0.2794)
			(stroke
				(width 0.1)
				(type default)
			)
			(layer "B.Fab")
		)
		(fp_line
			(start 0.12065 0.3048)
			(end 0.67945 0.3048)
			(stroke
				(width 0.1)
				(type default)
			)
			(layer "B.Fab")
		)
		(fp_line
			(start 0.67945 0.3048)
			(end 0.67945 -0.305054)
			(stroke
				(width 0.1)
				(type default)
			)
			(layer "B.Fab")
		)
		(fp_line
			(start -0.120396 0.2794)
			(end 0.12065 0.2794)
			(stroke
				(width 0.1)
				(type default)
			)
			(layer "B.Fab")
		)
		(fp_line
			(start 0.12065 0.2794)
			(end 0.12065 0.3048)
			(stroke
				(width 0.1)
				(type default)
			)
			(layer "B.Fab")
		)
		(fp_line
			(start -0.12065 -0.2794)
			(end -0.12065 -0.3048)
			(stroke
				(width 0.1)
				(type default)
			)
			(layer "B.Fab")
		)
		(fp_line
			(start 0.12065 -0.2794)
			(end -0.12065 -0.2794)
			(stroke
				(width 0.1)
				(type default)
			)
			(layer "B.Fab")
		)
		(fp_line
			(start -0.67945 -0.3048)
			(end -0.67945 0.3048)
			(stroke
				(width 0.1)
				(type default)
			)
			(layer "B.Fab")
		)
		(fp_line
			(start -0.12065 -0.3048)
			(end -0.67945 -0.3048)
			(stroke
				(width 0.1)
				(type default)
			)
			(layer "B.Fab")
		)
		(fp_line
			(start 0.12065 -0.305054)
			(end 0.12065 -0.2794)
			(stroke
				(width 0.1)
				(type default)
			)
			(layer "B.Fab")
		)
		(fp_line
			(start 0.67945 -0.305054)
			(end 0.12065 -0.305054)
			(stroke
				(width 0.1)
				(type default)
			)
			(layer "B.Fab")
		)
		(pad "1" smd circle
			(at 0.40005 0 90)
			(size 0 0)
			(layers "B.Cu" "B.Mask" "B.Paste")
			(net "HSC_VDD_R")
		)
		(pad "2" smd circle
			(at -0.40005 0 90)
			(size 0 0)
			(layers "B.Cu" "B.Mask" "B.Paste")
			(net "AGND_HSC")
		)
	)
	(footprint ""
		(layer "B.Cu")
		(at 257.63982 -49.430686 180)
		(property "Reference" "PR4541"
			(at 0 0 0)
			(layer "B.SilkS")
			(hide yes)
			(effects
				(font
					(size 1.27 1.27)
				)
				(justify mirror)
			)
		)
		(property "Value" ""
			(at 0 0 0)
			(layer "B.Fab")
			(effects
				(font
					(size 1.27 1.27)
				)
				(justify mirror)
			)
		)
		(duplicate_pad_numbers_are_jumpers no)
		(fp_line
			(start 0.7874 0.4064)
			(end 0.7874 -0.4064)
			(stroke
				(width 0.1524)
				(type default)
			)
			(layer "B.SilkS")
		)
		(fp_line
			(start 0.7874 -0.4064)
			(end -0.7874 -0.4064)
			(stroke
				(width 0.1524)
				(type default)
			)
			(layer "B.SilkS")
		)
		(fp_line
			(start -0.7874 0.4064)
			(end 0.7874 0.4064)
			(stroke
				(width 0.1524)
				(type default)
			)
			(layer "B.SilkS")
		)
		(fp_line
			(start -0.7874 -0.4064)
			(end -0.7874 0.4064)
			(stroke
				(width 0.1524)
				(type default)
			)
			(layer "B.SilkS")
		)
		(fp_line
			(start 0.67945 0.3048)
			(end 0.67945 -0.305054)
			(stroke
				(width 0.1)
				(type default)
			)
			(layer "B.Fab")
		)
		(fp_line
			(start 0.67945 -0.305054)
			(end 0.12065 -0.305054)
			(stroke
				(width 0.1)
				(type default)
			)
			(layer "B.Fab")
		)
		(fp_line
			(start 0.12065 0.3048)
			(end 0.67945 0.3048)
			(stroke
				(width 0.1)
				(type default)
			)
			(layer "B.Fab")
		)
		(fp_line
			(start 0.12065 0.2794)
			(end 0.12065 0.3048)
			(stroke
				(width 0.1)
				(type default)
			)
			(layer "B.Fab")
		)
		(fp_line
			(start 0.12065 -0.2794)
			(end -0.12065 -0.2794)
			(stroke
				(width 0.1)
				(type default)
			)
			(layer "B.Fab")
		)
		(fp_line
			(start 0.12065 -0.305054)
			(end 0.12065 -0.2794)
			(stroke
				(width 0.1)
				(type default)
			)
			(layer "B.Fab")
		)
		(fp_line
			(start -0.120396 0.3048)
			(end -0.120396 0.2794)
			(stroke
				(width 0.1)
				(type default)
			)
			(layer "B.Fab")
		)
		(fp_line
			(start -0.120396 0.2794)
			(end 0.12065 0.2794)
			(stroke
				(width 0.1)
				(type default)
			)
			(layer "B.Fab")
		)
		(fp_line
			(start -0.12065 -0.2794)
			(end -0.12065 -0.3048)
			(stroke
				(width 0.1)
				(type default)
			)
			(layer "B.Fab")
		)
		(fp_line
			(start -0.12065 -0.3048)
			(end -0.67945 -0.3048)
			(stroke
				(width 0.1)
				(type default)
			)
			(layer "B.Fab")
		)
		(fp_line
			(start -0.67945 0.3048)
			(end -0.120396 0.3048)
			(stroke
				(width 0.1)
				(type default)
			)
			(layer "B.Fab")
		)
		(fp_line
			(start -0.67945 -0.3048)
			(end -0.67945 0.3048)
			(stroke
				(width 0.1)
				(type default)
			)
			(layer "B.Fab")
		)
		(pad "1" smd circle
			(at 0.40005 0)
			(size 0 0)
			(layers "B.Cu" "B.Mask" "B.Paste")
			(net "P12V_E1S_ISET_0")
		)
		(pad "2" smd circle
			(at -0.40005 0)
			(size 0 0)
			(layers "B.Cu" "B.Mask" "B.Paste")
			(net "P12V_E1S_ISET_0_R")
		)
	)
)
